# S9S_MB_2U (Grand Teton) — schematic netlist excerpt (pin names and nets, part order shuffled) for the footprints in the layout excerpt that follows; sources: Cadence DE-HDL packaged netlist, KiCad conversion of 03242023_DA0F0TMBIJ0_F0T_Motherboard_J_brd_V01_OCP.brd

PR1297  Q_RES  8.87K 1% EMPTY  pkg 0402LF  page 272 : A = PVCCFA_EHV_FIVRA_CPU0_LSET4 ; B = GND
R3620  Q_RES  0 5% CHIP  pkg 0402LF  page 172 : A = INA230_3_A0 ; B = SMB_INA230_3_3V3AUX_SCL_R1
PC417  Q_CAPP  270UF 16V 20% OSCON  pkg THLF  page 289 : A = SW_P12V_PVCCFA_EHV_FIVRA_CPU1_L ; B = GND

(kicad_pcb
	(version 20260206)
	(generator "pcbnew")
	(generator_version "10.0")
	(general
		(thickness 1.6)
		(legacy_teardrops no)
	)
	(paper "A4")
	(title_block
		(title "03242023_DA0F0TMBIJ0_F0T_Motherboard_J_brd_V01_OCP.brd")
		(comment 1 "Grand Teton / footprints 2015-2017 of 6105")
	)
	(layers
		(0 "F.Cu" signal "TOP")
		(4 "In1.Cu" signal "GND")
		(6 "In2.Cu" signal "IN1")
		(8 "In3.Cu" signal "GND1")
		(10 "In4.Cu" signal "IN2")
		(12 "In5.Cu" signal "GND2")
		(14 "In6.Cu" signal "IN3")
		(16 "In7.Cu" signal "GND3")
		(18 "In8.Cu" signal "VCC")
		(20 "In9.Cu" signal "VCC1")
		(22 "In10.Cu" signal "GND4")
		(24 "In11.Cu" signal "IN4")
		(26 "In12.Cu" signal "GND5")
		(28 "In13.Cu" signal "IN5")
		(30 "In14.Cu" signal "GND6")
		(32 "In15.Cu" signal "IN6")
		(34 "In16.Cu" signal "GND7")
		(2 "B.Cu" signal "BOTTOM")
		(9 "F.Adhes" user "F.Adhesive")
		(11 "B.Adhes" user "B.Adhesive")
		(13 "F.Paste" user "Package Geometry/Pastemask Top")
		(15 "B.Paste" user "Package Geometry/Pastemask Bottom")
		(5 "F.SilkS" user "Ref Des/Silkscreen Top")
		(7 "B.SilkS" user "Ref Des/Silkscreen Bottom")
		(1 "F.Mask" user "Board Geometry/Soldermask Top")
		(3 "B.Mask" user "Board Geometry/Soldermask Bottom")
		(17 "Dwgs.User" user "User.Drawings")
		(19 "Cmts.User" user "User.Comments")
		(21 "Eco1.User" user "User.Eco1")
		(23 "Eco2.User" user "User.Eco2")
		(25 "Edge.Cuts" user "Board Geometry/Outline")
		(27 "Margin" user)
		(31 "F.CrtYd" user "Package Geometry/Place Bound Top")
		(29 "B.CrtYd" user "Package Geometry/Place Bound Bottom")
		(35 "F.Fab" user "Ref Des/Assembly Top")
		(33 "B.Fab" user "Ref Des/Assembly Bottom")
	)
	(footprint ""
		(layer "F.Cu")
		(at 287.494726 -367.919508)
		(property "Reference" "PR1297"
			(at 0 0 0)
			(layer "F.SilkS")
			(hide yes)
			(effects
				(font
					(size 1.27 1.27)
				)
			)
		)
		(property "Value" ""
			(at 0 0 0)
			(layer "F.Fab")
			(effects
				(font
					(size 1.27 1.27)
				)
			)
		)
		(duplicate_pad_numbers_are_jumpers no)
		(fp_line
			(start -0.7874 -0.4064)
			(end 0.7874 -0.4064)
			(stroke
				(width 0.1524)
				(type default)
			)
			(layer "F.SilkS")
		)
		(fp_line
			(start -0.7874 0.4064)
			(end -0.7874 -0.4064)
			(stroke
				(width 0.1524)
				(type default)
			)
			(layer "F.SilkS")
		)
		(fp_line
			(start 0.7874 -0.4064)
			(end 0.7874 0.4064)
			(stroke
				(width 0.1524)
				(type default)
			)
			(layer "F.SilkS")
		)
		(fp_line
			(start 0.7874 0.4064)
			(end -0.7874 0.4064)
			(stroke
				(width 0.1524)
				(type default)
			)
			(layer "F.SilkS")
		)
		(fp_line
			(start -0.67945 -0.305054)
			(end -0.12065 -0.305054)
			(stroke
				(width 0.1)
				(type default)
			)
			(layer "F.Fab")
		)
		(fp_line
			(start -0.67945 0.3048)
			(end -0.67945 -0.305054)
			(stroke
				(width 0.1)
				(type default)
			)
			(layer "F.Fab")
		)
		(fp_line
			(start -0.12065 -0.305054)
			(end -0.12065 -0.2794)
			(stroke
				(width 0.1)
				(type default)
			)
			(layer "F.Fab")
		)
		(fp_line
			(start -0.12065 -0.2794)
			(end 0.12065 -0.2794)
			(stroke
				(width 0.1)
				(type default)
			)
			(layer "F.Fab")
		)
		(fp_line
			(start -0.12065 0.2794)
			(end -0.12065 0.3048)
			(stroke
				(width 0.1)
				(type default)
			)
			(layer "F.Fab")
		)
		(fp_line
			(start -0.12065 0.3048)
			(end -0.67945 0.3048)
			(stroke
				(width 0.1)
				(type default)
			)
			(layer "F.Fab")
		)
		(fp_line
			(start 0.120396 0.2794)
			(end -0.12065 0.2794)
			(stroke
				(width 0.1)
				(type default)
			)
			(layer "F.Fab")
		)
		(fp_line
			(start 0.120396 0.3048)
			(end 0.120396 0.2794)
			(stroke
				(width 0.1)
				(type default)
			)
			(layer "F.Fab")
		)
		(fp_line
			(start 0.12065 -0.3048)
			(end 0.67945 -0.3048)
			(stroke
				(width 0.1)
				(type default)
			)
			(layer "F.Fab")
		)
		(fp_line
			(start 0.12065 -0.2794)
			(end 0.12065 -0.3048)
			(stroke
				(width 0.1)
				(type default)
			)
			(layer "F.Fab")
		)
		(fp_line
			(start 0.67945 -0.3048)
			(end 0.67945 0.3048)
			(stroke
				(width 0.1)
				(type default)
			)
			(layer "F.Fab")
		)
		(fp_line
			(start 0.67945 0.3048)
			(end 0.120396 0.3048)
			(stroke
				(width 0.1)
				(type default)
			)
			(layer "F.Fab")
		)
		(pad "1" smd circle
			(at -0.40005 0)
			(size 0 0)
			(layers "F.Cu" "F.Mask" "F.Paste")
			(net "PVCCFA_EHV_FIVRA_CPU0_LSET4")
		)
		(pad "2" smd circle
			(at 0.40005 0)
			(size 0 0)
			(layers "F.Cu" "F.Mask" "F.Paste")
			(net "GND")
		)
	)
	(footprint ""
		(layer "F.Cu")
		(at 68.212462 -38.405562 180)
		(property "Reference" "R3620"
			(at 0 0 180)
			(layer "F.SilkS")
			(hide yes)
			(effects
				(font
					(size 1.27 1.27)
				)
			)
		)
		(property "Value" ""
			(at 0 0 180)
			(layer "F.Fab")
			(effects
				(font
					(size 1.27 1.27)
				)
			)
		)
		(duplicate_pad_numbers_are_jumpers no)
		(fp_line
			(start 0.7874 0.4064)
			(end -0.7874 0.4064)
			(stroke
				(width 0.1524)
				(type default)
			)
			(layer "F.SilkS")
		)
		(fp_line
			(start 0.7874 -0.4064)
			(end 0.7874 0.4064)
			(stroke
				(width 0.1524)
				(type default)
			)
			(layer "F.SilkS")
		)
		(fp_line
			(start -0.7874 0.4064)
			(end -0.7874 -0.4064)
			(stroke
				(width 0.1524)
				(type default)
			)
			(layer "F.SilkS")
		)
		(fp_line
			(start -0.7874 -0.4064)
			(end 0.7874 -0.4064)
			(stroke
				(width 0.1524)
				(type default)
			)
			(layer "F.SilkS")
		)
		(fp_line
			(start 0.67945 0.3048)
			(end 0.120396 0.3048)
			(stroke
				(width 0.1)
				(type default)
			)
			(layer "F.Fab")
		)
		(fp_line
			(start 0.67945 -0.3048)
			(end 0.67945 0.3048)
			(stroke
				(width 0.1)
				(type default)
			)
			(layer "F.Fab")
		)
		(fp_line
			(start 0.12065 -0.2794)
			(end 0.12065 -0.3048)
			(stroke
				(width 0.1)
				(type default)
			)
			(layer "F.Fab")
		)
		(fp_line
			(start 0.12065 -0.3048)
			(end 0.67945 -0.3048)
			(stroke
				(width 0.1)
				(type default)
			)
			(layer "F.Fab")
		)
		(fp_line
			(start 0.120396 0.3048)
			(end 0.120396 0.2794)
			(stroke
				(width 0.1)
				(type default)
			)
			(layer "F.Fab")
		)
		(fp_line
			(start 0.120396 0.2794)
			(end -0.12065 0.2794)
			(stroke
				(width 0.1)
				(type default)
			)
			(layer "F.Fab")
		)
		(fp_line
			(start -0.12065 0.3048)
			(end -0.67945 0.3048)
			(stroke
				(width 0.1)
				(type default)
			)
			(layer "F.Fab")
		)
		(fp_line
			(start -0.12065 0.2794)
			(end -0.12065 0.3048)
			(stroke
				(width 0.1)
				(type default)
			)
			(layer "F.Fab")
		)
		(fp_line
			(start -0.12065 -0.2794)
			(end 0.12065 -0.2794)
			(stroke
				(width 0.1)
				(type default)
			)
			(layer "F.Fab")
		)
		(fp_line
			(start -0.12065 -0.305054)
			(end -0.12065 -0.2794)
			(stroke
				(width 0.1)
				(type default)
			)
			(layer "F.Fab")
		)
		(fp_line
			(start -0.67945 0.3048)
			(end -0.67945 -0.305054)
			(stroke
				(width 0.1)
				(type default)
			)
			(layer "F.Fab")
		)
		(fp_line
			(start -0.67945 -0.305054)
			(end -0.12065 -0.305054)
			(stroke
				(width 0.1)
				(type default)
			)
			(layer "F.Fab")
		)
		(pad "1" smd circle
			(at -0.40005 0 180)
			(size 0 0)
			(layers "F.Cu" "F.Mask" "F.Paste")
			(net "INA230_3_A0")
		)
		(pad "2" smd circle
			(at 0.40005 0 180)
			(size 0 0)
			(layers "F.Cu" "F.Mask" "F.Paste")
			(net "SMB_INA230_3_3V3AUX_SCL_R1")
		)
	)
	(footprint ""
		(layer "F.Cu")
		(at 49.610264 -363.228636 90)
		(property "Reference" "PC417"
			(at 0 0 90)
			(layer "F.SilkS")
			(hide yes)
			(effects
				(font
					(size 1.27 1.27)
				)
			)
		)
		(property "Value" ""
			(at 0 0 90)
			(layer "F.Fab")
			(effects
				(font
					(size 1.27 1.27)
				)
			)
		)
		(duplicate_pad_numbers_are_jumpers no)
		(fp_line
			(start -3.400044 1.249934)
			(end 3.400044 1.249934)
			(stroke
				(width 0.1524)
				(type default)
			)
			(layer "F.SilkS")
		)
		(fp_circle
			(center 0 1.249934)
			(end 0 4.649978)
			(stroke
				(width 0.1524)
				(type default)
			)
			(fill no)
			(layer "F.SilkS")
		)
		(fp_poly
			(pts
				(arc
					(start -3.400044 1.249934)
					(mid 0 4.649978)
					(end 3.400044 1.249934)
				)
			)
			(stroke
				(width 0)
				(type default)
			)
			(fill yes)
			(layer "F.SilkS")
		)
		(fp_circle
			(center 0 1.249934)
			(end 0 4.649978)
			(stroke
				(width 0.1)
				(type default)
			)
			(fill no)
			(layer "F.Fab")
		)
		(pad "1" thru_hole rect
			(at 0 0 90)
			(size 1.524 1.524)
			(drill 1.016)
			(layers "*.Cu" "*.Mask")
			(remove_unused_layers no)
			(net "SW_P12V_PVCCFA_EHV_FIVRA_CPU1_L")
			(clearance 0)
			(padstack
				(mode front_inner_back)
				(layer "Inner"
					(shape circle)
					(size 1.524 1.524)
					(clearance 0)
				)
				(layer "B.Cu"
					(shape rect)
					(size 1.524 1.524)
					(clearance 0)
				)
			)
		)
		(pad "2" thru_hole circle
			(at 0 2.500122 90)
			(size 1.524 1.524)
			(drill 1.016)
			(layers "*.Cu" "*.Mask")
			(remove_unused_layers no)
			(net "GND")
			(clearance 0)
		)
	)
)
